FILE_TYPE = MULTI_PHYS_TABLE;
PART 'MOSFET_N'
{================================================================================================================================================================================================================================================}
:VALUE        | PACK_TYPE | MATERIAL | PART_NUMBER     = EnvComp                  |  PART_NUMBER | JEDEC_TYPE    | ALT_SYMBOLS  | CLASS | DESCRIPTION                       | HEIGHT     | COMPONENT_TYPE | LEAD_LENGTH| LPID    | SPEED_URL | Status |RPL| AML | Bus_Unit | Days ;
{==================================================================================================================================================================================================================================================}
'BSZ019N03LS' | 'LCC3'    | 'NFET'   | 'G26762-001'(!) = ''                       | 'G26762-001' |'MLFP3_13_65MA'| ''           | 'IC'  | 'IC,DS,FET N,E-SO8,BSZ019N03L'    | '0.043 IN' | 'LCC'          | ''         | '2389'  | 'http://speed.intel.com:8081/speed/module/pdm/item/pdm_item_detail_direct.asp?item_cde=G26762-001&item_rev=01&url_param=unused' | '' | '' | '' | '' | '' 
'BSZ019N03LS' | 'LCC3'    | 'EMPTY'  | 'G26762-001'(!) = ''                       | 'G26762-001' |'MLFP3_13_65MA'| ''           | 'IO'  | 'IC,DS,FET N,E-SO8,BSZ019N03L'    | '0.043 IN' | 'LCC'          | ''         | '2389'  | 'http://speed.intel.com:8081/speed/module/pdm/item/pdm_item_detail_direct.asp?item_cde=G26762-001&item_rev=01&url_param=unused' | '' | '' | '' | '' | '' 
END_PART
END.
